FILE_TYPE = CONNECTIVITY;
{Allegro Design Entry HDL 16.6-p007 (v16-6-112F) 10/10/2012}
"PAGE_NUMBER" = 136;
0"NC";
1"GND\g";
2"P3V3_STBY\g";
3"P3V3_STBY\g";
4"GND\g";
5"P3V3_STBY\g";
6"GND\g";
7"GND\g";
8"GND\g";
9"P3V3_STBY\g";
10"GND\g";
11"RST_PLTRST_N";
12"FM_BIOS_TOP_SWAP";
13"PD_ME_RCVR_N";
14"TP_ME_RCVR_BOOT";
15"FM_ME_RECOVER_N";
16"TP_PASSWORD_CLEAR";
17"PD_PASSWORD_CLEAR";
18"FM_PASSWORD_CLEAR_N";
19"PU_BIOS_USB_RECOVERY";
20"TP_BIOS_USB_RECOVERY";
21"TP_BIOS_RECOVER_BOOT";
22"PU_BIOS_RECOVER_BOOT";
23"FM_BIOS_USB_RECOVERY";
24"FM_BIOS_TOP_SWAP";
25"RST_PLTRST_TOP_SWAP";
26"FM_BIOS_TOP_SWAP_SPKR_R";
27"FM_BIOS_TOP_SWAP_SPKR";
%"RES"
"2","(-2250,4800)","0","mstr_discrete","I101";
;
CDS_SEC"1"
CDS_LOCATION"R7G26"
ROOM"SB"
CDS_LIB"mstr_discrete"
SEC_TYPE"0402"
SEC"1"
LOCATION"R7G26"
PART_NUMBER"G21796-016"
VALUE"10.0K"
TOLERANCE"1%"
PACK_TYPE"0402"
MATERIAL"CHIP"
WATTAGE"1/16W";
"A"
$PN"1"2;
"B"
$PN"2"15;
%"RES"
"2","(-2250,3825)","0","mstr_discrete","I102";
;
CDS_SEC"1"
CDS_LOCATION"R7G28"
ROOM"SB"
SEC"1"
SEC_TYPE"0402"
BOM_COST"SB"
CDS_LIB"mstr_discrete"
LOCATION"R7G28"
PART_NUMBER"G21796-026"
VALUE"1.00K"
TOLERANCE"1%"
PACK_TYPE"0402"
MATERIAL"CHIP"
WATTAGE"1/16W";
"A"
$PN"1"13;
"B"
$PN"2"1;
%"GND"
"1","(-2250,3625)","0","mstr_symbols","I103";
;
VOLTAGE"0"
HDL_POWER"GND"
SIZE"1B"
BOM_COST"SB"
CDS_LIB"mstr_symbols"
BODY_TYPE"PLUMBING";
"A\NAC"1;
%"P3V3_STBY"
"1","(-2250,5025)","0","mstr_symbols","I124";
;
VOLTAGE"3.3V"
HDL_POWER"P3V3_STBY"
BODY_TYPE"PLUMBING"
CDS_LIB"mstr_symbols"
SIZE"1B";
"G\NAC"2;
%"RES"
"1","(1000,2300)","0","mstr_discrete","I126";
;
CDS_SEC"1"
ROOM"SB"
CDS_LOCATION"R8E20"
SEC"1"
BOM_COST"SB"
SEC_TYPE"0402"
CDS_LIB"mstr_discrete"
LOCATION"R8E20"
PART_NUMBER"G21796-074"
VALUE"33.2"
TOLERANCE"1%"
PACK_TYPE"0402"
MATERIAL"CHIP"
WATTAGE"1/16W";
"B"
$PN"2"27;
"A"
$PN"1"26;
%"P3V3_STBY"
"1","(575,1825)","0","mstr_symbols","I127";
;
VOLTAGE"3.3V"
HDL_POWER"P3V3_STBY"
BODY_TYPE"PLUMBING"
CDS_LIB"mstr_symbols"
SIZE"1B";
"G\NAC"3;
%"CAP_A"
"1","(575,1575)","0","dev_discrete","I128";
;
ROOM"SB"
SEC"1"
SEC_TYPE"0402V"
CDS_SEC"1"
CDS_LIB"dev_discrete"
BOM_COST"SB"
CDS_LOCATION"C8E8"
LOCATION"C8E8"
PART_NUMBER"A36096-030"
VALUE"0.1UF"
TOLERANCE"10%"
PACK_TYPE"0402V"
VOLTAGE"16V"
MATERIAL"X7R";
"B"
$PN"2"4;
"A"
$PN"1"3;
%"GND"
"1","(575,1300)","0","mstr_symbols","I129";
;
VOLTAGE"0.0V"
HDL_POWER"GND"
BODY_TYPE"PLUMBING"
CDS_LIB"mstr_symbols"
SIZE"1B";
"A\NAC"4;
%"TTL1G126_A"
"1","(0,2300)","0","mstr_ttl","I130";
;
CDS_SEC"1"
PACK_TYPE"SOT"
ROOM"SB"
CDS_LOCATION"U8E3"
SEC"1"
CDS_LIB"mstr_ttl"
SEC_TYPE"SOT"
BOM_COST"SB"
POWER_GROUP"VCC=P3V3_STBY;GND=GND;"
LOCATION"U8E3"
PART_NUMBER"A79322-001"
VALUE"74HC1G126"
MATERIAL"IC";
"OE"
$PN"1"25;
"Y"
$PN"4"26;
"A"
$PN"2"12;
%"P3V3_STBY"
"1","(-550,2100)","0","mstr_symbols","I131";
;
VOLTAGE"3.3V"
HDL_POWER"P3V3_STBY"
BODY_TYPE"PLUMBING"
CDS_LIB"mstr_symbols"
SIZE"1B";
"G\NAC"5;
%"RES"
"2","(-550,1900)","0","mstr_discrete","I133";
;
CDS_SEC"1"
ROOM"SB"
CDS_LOCATION"R8E14"
SEC"1"
SEC_TYPE"0402"
CDS_LIB"mstr_discrete"
LOCATION"R8E14"
PART_NUMBER"G21796-072"
VALUE"4.75K"
TOLERANCE"1%"
PACK_TYPE"0402"
MATERIAL"CHIP"
WATTAGE"1/16W";
"A"
$PN"1"5;
"B"
$PN"2"25;
%"FET_N"
"8","(-550,1375)","0","mstr_discrete","I134";
;
CDS_SEC"1"
PACK_TYPE"SOT23LF"
ROOM"SB"
CDS_LOCATION"Q8E1"
SEC"1"
SEC_TYPE"SOT23LF"
CDS_LIB"mstr_discrete"
LOCATION"Q8E1"
PART_NUMBER"C79254-001"
VALUE"2N7002"
MATERIAL"FET";
"GATE"
$PN"1"11;
"DRN"
$PN"3"25;
"SRC"
$PN"2"6;
%"GND"
"1","(-550,1075)","0","mstr_symbols","I135";
;
VOLTAGE"0.0V"
HDL_POWER"GND"
BODY_TYPE"PLUMBING"
CDS_LIB"mstr_symbols"
SIZE"1B";
"A\NAC"6;
%"RES"
"2","(-775,4800)","0","mstr_discrete","I139";
;
CDS_SEC"1"
CDS_LOCATION"R7G31"
ROOM"SB"
CDS_LIB"mstr_discrete"
BOM_COST"SB"
SEC_TYPE"0402"
SEC"1"
LOCATION"R7G31"
PART_NUMBER"G21796-026"
VALUE"1.00K"
TOLERANCE"1%"
PACK_TYPE"0402"
MATERIAL"CHIP"
WATTAGE"1/16W";
"A"
$PN"1"9;
"B"
$PN"2"22;
%"RES"
"2","(-425,3825)","0","mstr_discrete","I140";
;
CDS_SEC"1"
ROOM"SB"
CDS_LOCATION"R8E16"
BOM_COST"SB"
CDS_LIB"mstr_discrete"
SEC_TYPE"0402"
SEC"1"
LOCATION"R8E16"
PART_NUMBER"G21796-040"
VALUE"20.0K"
TOLERANCE"1%"
PACK_TYPE"0402"
MATERIAL"CHIP"
WATTAGE"1/16W";
"A"
$PN"1"24;
"B"
$PN"2"7;
%"GND"
"1","(-425,3625)","0","mstr_symbols","I141";
;
VOLTAGE"0"
HDL_POWER"GND"
ROOM"WBG_HEADERS_BIOS"
CDS_LIB"mstr_symbols"
SIZE"1B"
BOM_COST"SB"
BODY_TYPE"PLUMBING";
"A\NAC"7;
%"RES"
"2","(-2650,4800)","2","mstr_discrete","I147";
;
CDS_SEC"1"
CDS_LOCATION"R2N28"
ROOM"SB"
CDS_LIB"mstr_discrete"
BOM_COST"SB"
SEC_TYPE"0402"
SEC"1"
LOCATION"R2N28"
PART_NUMBER"G21796-016"
VALUE"10.0K"
TOLERANCE"1%"
PACK_TYPE"0402"
MATERIAL"CHIP"
WATTAGE"1/16W";
"A"
$PN"1"2;
"B"
$PN"2"18;
%"RES"
"2","(-2650,3825)","0","mstr_discrete","I148";
;
CDS_SEC"1"
CDS_LOCATION"R7G29"
ROOM"SB"
CDS_LIB"mstr_discrete"
BOM_COST"SB"
SEC_TYPE"0402"
SEC"1"
LOCATION"R7G29"
PART_NUMBER"G21796-026"
VALUE"1.00K"
TOLERANCE"1%"
PACK_TYPE"0402"
MATERIAL"CHIP"
WATTAGE"1/16W";
"A"
$PN"1"17;
"B"
$PN"2"8;
%"GND"
"1","(-2650,3625)","0","mstr_symbols","I152";
;
VOLTAGE"0"
HDL_POWER"GND"
ROOM"WBG_HEADERS_BIOS"
BODY_TYPE"PLUMBING"
BOM_COST"SB"
CDS_LIB"mstr_symbols"
SIZE"1B";
"A\NAC"8;
%"P3V3_STBY"
"1","(-1075,5025)","0","mstr_symbols","I154";
;
VOLTAGE"3.3V"
HDL_POWER"P3V3_STBY"
BODY_TYPE"PLUMBING"
SIZE"1B"
CDS_LIB"mstr_symbols";
"G\NAC"9;
%"RES"
"2","(-1075,4800)","2","mstr_discrete","I155";
;
CDS_SEC"1"
CDS_LOCATION"R7G27"
ROOM"SB"
SEC_TYPE"0402"
BOM_COST"SB"
CDS_LIB"mstr_discrete"
SEC"1"
LOCATION"R7G27"
PART_NUMBER"G21796-026"
VALUE"1.00K"
TOLERANCE"1%"
PACK_TYPE"0402"
MATERIAL"CHIP"
WATTAGE"1/16W";
"A"
$PN"1"9;
"B"
$PN"2"19;
%"RES"
"2","(-725,3825)","0","mstr_discrete","I156";
;
CDS_SEC"1"
CDS_LOCATION"R3T14"
ROOM"SB"
SEC_TYPE"0402"
CDS_LIB"mstr_discrete"
BOM_COST"SB"
SEC"1"
LOCATION"R3T14"
PART_NUMBER"G21796-016"
VALUE"10.0K"
TOLERANCE"1%"
PACK_TYPE"0402"
MATERIAL"CHIP"
WATTAGE"1/16W";
"A"
$PN"1"23;
"B"
$PN"2"10;
%"GND"
"1","(-725,3625)","0","mstr_symbols","I157";
;
VOLTAGE"0"
HDL_POWER"GND"
SIZE"1B"
BOM_COST"SB"
CDS_LIB"mstr_symbols"
BODY_TYPE"PLUMBING";
"A\NAC"10;
%"CONN12_C73564003"
"1","(-1650,4250)","0","mstr_conn","I174";
;
CDS_SEC"1"
CDS_LOCATION"J7G3"
PACK_TYPE"PIP"
ROOM"SB"
SEC_TYPE"PIP"
SEC"1"
CDS_LIB"mstr_conn"
BOM_COST"SB"
LOCATION"J7G3"
PART_NUMBER"C73564-003"
MATERIAL"CONN";
"IO9"
$PN"9"18;
"IO11"
$PN"11"17;
"IO7"
$PN"7"16;
"IO3"
$PN"3"15;
"IO1"
$PN"1"14;
"IO5"
$PN"5"13;
"IO8"
$PN"8"21;
"IO10"
$PN"10"24;
"IO12"
$PN"12"22;
"IO6"
$PN"6"19;
"IO4"
$PN"4"23;
"IO2"
$PN"2"20;
END.
